#ISCELL
  mstr_misc dns *
  *
#ISCELL
  pure_quanta quanta_title_block_c *
  *
#ISCELL
  logical_power universal_gnd *
  page283_i1
#CELL
  pure_quanta isl99390frztr5935 *
  page283_i10
#ISCELL
  logical_power universal_gnd *
  page283_i11
#CELL
  pure_quanta q_res *
  page283_i12
#CELL
  pure_quanta q_cap *
  page283_i13
#CELL
  pure_quanta q_inductor *
  page283_i14
#CELL
  pure_quanta q_cap *
  page283_i15
#CELL
  pure_quanta q_res *
  page283_i16
#ISCELL
  logical_power vcc15 *
  page283_i17
#CELL
  pure_quanta q_cap *
  page283_i18
#ISCELL
  logical_power universal_gnd *
  page283_i19
#ISCELL
  logical_power universal_gnd *
  page283_i2
#CELL
  pure_quanta q_cap *
  page283_i20
#CELL
  pure_quanta q_res *
  page283_i21
#CELL
  pure_quanta q_cap *
  page283_i22
#CELL
  pure_quanta q_cap *
  page283_i23
#CELL
  pure_quanta q_cap *
  page283_i24
#CELL
  pure_quanta q_capp *
  page283_i25
#CELL
  pure_quanta q_capp *
  page283_i26
#CELL
  pure_quanta q_cap *
  page283_i27
#CELL
  pure_quanta q_cap *
  page283_i28
#CELL
  pure_quanta q_cap *
  page283_i29
#CELL
  pure_quanta q_res *
  page283_i3
#CELL
  pure_quanta q_cap *
  page283_i30
#ISCELL
  logical_power universal_gnd *
  page283_i31
#CELL
  pure_quanta q_capp *
  page283_i32
#ISCELL
  logical_power vcc15 *
  page283_i33
#ISCELL
  logical_power universal_gnd *
  page283_i34
#CELL
  pure_quanta q_res *
  page283_i35
#ISCELL
  logical_power vcc15 *
  page283_i36
#ISCELL
  logical_power universal_gnd *
  page283_i37
#ISCELL
  logical_power vcc15 *
  page283_i38
#ISCELL
  standard offpage *
  page283_i4
#ISCELL
  standard offpage *
  page283_i5
#ISCELL
  standard offpage *
  page283_i6
#ISCELL
  standard offpage *
  page283_i7
#CELL
  pure_quanta q_cap *
  page283_i8
#ISCELL
  logical_power universal_gnd *
  page283_i9
